# S9S_MB_2U (Grand Teton) — schematic netlist excerpt (pin names and nets, part order shuffled) for the footprints in the layout excerpt that follows; sources: Cadence DE-HDL packaged netlist, KiCad conversion of 03242023_DA0F0TMBIJ0_F0T_Motherboard_J_brd_V01_OCP.brd

U5201  TUSB211IRWBR  EMPTY  pkg X2QFN12_0-4_1-6X1-6  page 152
  D1M  = USB2_HUB_BUF_SWB_R_DN
  D1P  = USB2_HUB_BUF_SWB_R_DP
  TEST  = TP_USB2_TEST
  CD  = TP_USB2_CD
  RSTN  = PD_U5201_RSTN
  EQ  = PD_U5201_EQ
  D2P  = USB2_HUB_BUF_SWB_R_DP
  D2M  = USB2_HUB_BUF_SWB_R_DN
  ENA_HS  = TP_USB2_ENA_HS
  GND  = GND
  VREG  = PD_U5201_VREG
  VCC  = P3V3_AUX

PC413_P1_2  Q_CAP  22UF 4V 20% X6S  pkg C0805  page 289 : A = PVCCFA_EHV_FIVRA_CPU1 ; B = GND
C163  Q_CAP_DIFFBUS  DIFF BUS_0.22UF 6.3V 20% X6S  pkg C0201  page 178 : \1\ = DMI_CPU0_PCH_RX_C_DN<3> ; \2\ = DMI_CPU0_PCH_RX_DN<3>

(kicad_pcb
	(version 20260206)
	(generator "pcbnew")
	(generator_version "10.0")
	(general
		(thickness 1.6)
		(legacy_teardrops no)
	)
	(paper "A4")
	(title_block
		(title "03242023_DA0F0TMBIJ0_F0T_Motherboard_J_brd_V01_OCP.brd")
		(comment 1 "Grand Teton / footprints 5718-5720 of 6105")
	)
	(layers
		(0 "F.Cu" signal "TOP")
		(4 "In1.Cu" signal "GND")
		(6 "In2.Cu" signal "IN1")
		(8 "In3.Cu" signal "GND1")
		(10 "In4.Cu" signal "IN2")
		(12 "In5.Cu" signal "GND2")
		(14 "In6.Cu" signal "IN3")
		(16 "In7.Cu" signal "GND3")
		(18 "In8.Cu" signal "VCC")
		(20 "In9.Cu" signal "VCC1")
		(22 "In10.Cu" signal "GND4")
		(24 "In11.Cu" signal "IN4")
		(26 "In12.Cu" signal "GND5")
		(28 "In13.Cu" signal "IN5")
		(30 "In14.Cu" signal "GND6")
		(32 "In15.Cu" signal "IN6")
		(34 "In16.Cu" signal "GND7")
		(2 "B.Cu" signal "BOTTOM")
		(9 "F.Adhes" user "F.Adhesive")
		(11 "B.Adhes" user "B.Adhesive")
		(13 "F.Paste" user "Package Geometry/Pastemask Top")
		(15 "B.Paste" user "Package Geometry/Pastemask Bottom")
		(5 "F.SilkS" user "Ref Des/Silkscreen Top")
		(7 "B.SilkS" user "Ref Des/Silkscreen Bottom")
		(1 "F.Mask" user "Board Geometry/Soldermask Top")
		(3 "B.Mask" user "Board Geometry/Soldermask Bottom")
		(17 "Dwgs.User" user "User.Drawings")
		(19 "Cmts.User" user "User.Comments")
		(21 "Eco1.User" user "User.Eco1")
		(23 "Eco2.User" user "User.Eco2")
		(25 "Edge.Cuts" user "Board Geometry/Outline")
		(27 "Margin" user)
		(31 "F.CrtYd" user "Package Geometry/Place Bound Top")
		(29 "B.CrtYd" user "Package Geometry/Place Bound Bottom")
		(35 "F.Fab" user "Ref Des/Assembly Top")
		(33 "B.Fab" user "Ref Des/Assembly Bottom")
	)
	(footprint ""
		(layer "B.Cu")
		(at 12.076684 -112.319308 -90)
		(property "Reference" "U5201"
			(at -3.494532 -1.880616 0)
			(unlocked yes)
			(layer "B.SilkS")
			(effects
				(font
					(size 0.7874 0.5842)
					(thickness 0.1524)
				)
				(justify left mirror)
			)
		)
		(property "Value" ""
			(at 0 0 90)
			(layer "B.Fab")
			(effects
				(font
					(size 1.27 1.27)
				)
				(justify mirror)
			)
		)
		(duplicate_pad_numbers_are_jumpers no)
		(fp_line
			(start -1.2446 1.2446)
			(end -1.2446 0.479044)
			(stroke
				(width 0.1524)
				(type default)
			)
			(layer "B.SilkS")
		)
		(fp_line
			(start 1.2446 1.2446)
			(end -1.2446 1.2446)
			(stroke
				(width 0.1524)
				(type default)
			)
			(layer "B.SilkS")
		)
		(fp_line
			(start 1.2446 0.593344)
			(end 1.2446 1.2446)
			(stroke
				(width 0.1524)
				(type default)
			)
			(layer "B.SilkS")
		)
		(fp_line
			(start -1.2446 -0.506476)
			(end -1.2446 -1.2446)
			(stroke
				(width 0.1524)
				(type default)
			)
			(layer "B.SilkS")
		)
		(fp_line
			(start -1.2446 -1.2446)
			(end 1.2446 -1.2446)
			(stroke
				(width 0.1524)
				(type default)
			)
			(layer "B.SilkS")
		)
		(fp_line
			(start 1.2446 -1.2446)
			(end 1.2446 -0.592836)
			(stroke
				(width 0.1524)
				(type default)
			)
			(layer "B.SilkS")
		)
		(fp_poly
			(pts
				(xy 1.416812 -0.430022) (xy 1.688592 -1.246124) (xy 2.23266 -0.702056)
			)
			(stroke
				(width 0)
				(type default)
			)
			(fill yes)
			(layer "B.SilkS")
		)
		(fp_line
			(start -0.824992 0.824992)
			(end -0.824992 -0.824992)
			(stroke
				(width 0.1)
				(type default)
			)
			(layer "B.Fab")
		)
		(fp_line
			(start 0.824992 0.824992)
			(end -0.824992 0.824992)
			(stroke
				(width 0.1)
				(type default)
			)
			(layer "B.Fab")
		)
		(fp_line
			(start -0.824992 -0.824992)
			(end 0.824992 -0.824992)
			(stroke
				(width 0.1)
				(type default)
			)
			(layer "B.Fab")
		)
		(fp_line
			(start 0.824992 -0.824992)
			(end 0.824992 0.824992)
			(stroke
				(width 0.1)
				(type default)
			)
			(layer "B.Fab")
		)
		(fp_poly
			(pts
				(xy 1.389634 -0.199898) (xy 2.159 0.184658) (xy 2.159 -0.584708)
			)
			(stroke
				(width 0)
				(type default)
			)
			(fill yes)
			(layer "B.Fab")
		)
		(pad "1" smd rect
			(at 0.700024 -0.199898 180)
			(size 0.1778 0.8128)
			(layers "B.Cu" "B.Mask" "B.Paste")
			(net "USB2_HUB_BUF_SWB_R_DN")
		)
		(pad "2" smd rect
			(at 0.700024 0.199898 180)
			(size 0.1778 0.8128)
			(layers "B.Cu" "B.Mask" "B.Paste")
			(net "USB2_HUB_BUF_SWB_R_DP")
		)
		(pad "3" smd rect
			(at 0.599948 0.8001 90)
			(size 0.1778 0.6096)
			(layers "B.Cu" "B.Mask" "B.Paste")
			(net "TP_USB2_TEST")
		)
		(pad "4" smd rect
			(at 0.199898 0.8001 90)
			(size 0.1778 0.6096)
			(layers "B.Cu" "B.Mask" "B.Paste")
			(net "TP_USB2_CD")
		)
		(pad "5" smd rect
			(at -0.199898 0.8001 90)
			(size 0.1778 0.6096)
			(layers "B.Cu" "B.Mask" "B.Paste")
			(net "PD_U5201_RSTN")
		)
		(pad "6" smd rect
			(at -0.599948 0.8001 90)
			(size 0.1778 0.6096)
			(layers "B.Cu" "B.Mask" "B.Paste")
			(net "PD_U5201_EQ")
		)
		(pad "7" smd rect
			(at -0.700024 0.199898 180)
			(size 0.1778 0.8128)
			(layers "B.Cu" "B.Mask" "B.Paste")
			(net "USB2_HUB_BUF_SWB_R_DP")
		)
		(pad "8" smd rect
			(at -0.700024 -0.199898 180)
			(size 0.1778 0.8128)
			(layers "B.Cu" "B.Mask" "B.Paste")
			(net "USB2_HUB_BUF_SWB_R_DN")
		)
		(pad "9" smd rect
			(at -0.599948 -0.8001 90)
			(size 0.1778 0.6096)
			(layers "B.Cu" "B.Mask" "B.Paste")
			(net "TP_USB2_ENA_HS")
		)
		(pad "10" smd rect
			(at -0.199898 -0.8001 90)
			(size 0.1778 0.6096)
			(layers "B.Cu" "B.Mask" "B.Paste")
			(net "GND")
		)
		(pad "11" smd rect
			(at 0.199898 -0.8001 90)
			(size 0.1778 0.6096)
			(layers "B.Cu" "B.Mask" "B.Paste")
			(net "PD_U5201_VREG")
		)
		(pad "12" smd rect
			(at 0.599948 -0.8001 90)
			(size 0.1778 0.6096)
			(layers "B.Cu" "B.Mask" "B.Paste")
			(net "P3V3_AUX")
		)
	)
	(footprint ""
		(layer "B.Cu")
		(at 343.166192 -64.088264 90)
		(property "Reference" "C163"
			(at 0 0 90)
			(layer "B.SilkS")
			(hide yes)
			(effects
				(font
					(size 1.27 1.27)
				)
				(justify mirror)
			)
		)
		(property "Value" ""
			(at 0 0 90)
			(layer "B.Fab")
			(effects
				(font
					(size 1.27 1.27)
				)
				(justify mirror)
			)
		)
		(duplicate_pad_numbers_are_jumpers no)
		(fp_line
			(start 0.299974 -0.150114)
			(end -0.299974 -0.150114)
			(stroke
				(width 0.1)
				(type default)
			)
			(layer "B.Fab")
		)
		(fp_line
			(start -0.299974 -0.150114)
			(end -0.299974 0.150114)
			(stroke
				(width 0.1)
				(type default)
			)
			(layer "B.Fab")
		)
		(fp_line
			(start 0.299974 0.150114)
			(end 0.299974 -0.150114)
			(stroke
				(width 0.1)
				(type default)
			)
			(layer "B.Fab")
		)
		(fp_line
			(start -0.299974 0.150114)
			(end 0.299974 0.150114)
			(stroke
				(width 0.1)
				(type default)
			)
			(layer "B.Fab")
		)
		(pad "1" smd rect
			(at 0.2667 0 270)
			(size 0.3048 0.381)
			(layers "B.Cu" "B.Mask" "B.Paste")
			(net "DMI_CPU0_PCH_RX_C_DN<3>")
		)
		(pad "2" smd rect
			(at -0.2667 0 270)
			(size 0.3048 0.381)
			(layers "B.Cu" "B.Mask" "B.Paste")
			(net "DMI_CPU0_PCH_RX_DN<3>")
		)
	)
	(footprint ""
		(layer "B.Cu")
		(at 47.80661 -344.935556 -90)
		(property "Reference" "PC413_P1_2"
			(at 0 0 90)
			(layer "B.SilkS")
			(hide yes)
			(effects
				(font
					(size 1.27 1.27)
				)
				(justify mirror)
			)
		)
		(property "Value" ""
			(at 0 0 90)
			(layer "B.Fab")
			(effects
				(font
					(size 1.27 1.27)
				)
				(justify mirror)
			)
		)
		(duplicate_pad_numbers_are_jumpers no)
		(fp_line
			(start -1.524 0.762)
			(end 1.524 0.762)
			(stroke
				(width 0.1524)
				(type default)
			)
			(layer "B.SilkS")
		)
		(fp_line
			(start 1.524 0.762)
			(end 1.524 -0.762)
			(stroke
				(width 0.1524)
				(type default)
			)
			(layer "B.SilkS")
		)
		(fp_line
			(start -1.524 -0.762)
			(end -1.524 0.762)
			(stroke
				(width 0.1524)
				(type default)
			)
			(layer "B.SilkS")
		)
		(fp_line
			(start 1.524 -0.762)
			(end -1.524 -0.762)
			(stroke
				(width 0.1524)
				(type default)
			)
			(layer "B.SilkS")
		)
		(fp_line
			(start -1.1049 0.724916)
			(end -1.1049 -0.724916)
			(stroke
				(width 0.1)
				(type default)
			)
			(layer "B.Fab")
		)
		(fp_line
			(start 1.1049 0.724916)
			(end -1.1049 0.724916)
			(stroke
				(width 0.1)
				(type default)
			)
			(layer "B.Fab")
		)
		(fp_line
			(start -1.1049 -0.724916)
			(end 1.1049 -0.724916)
			(stroke
				(width 0.1)
				(type default)
			)
			(layer "B.Fab")
		)
		(fp_line
			(start 1.1049 -0.724916)
			(end 1.1049 0.724916)
			(stroke
				(width 0.1)
				(type default)
			)
			(layer "B.Fab")
		)
		(pad "1" smd rect
			(at 0.889 0 270)
			(size 1.016 1.27)
			(layers "B.Cu" "B.Mask" "B.Paste")
			(net "PVCCFA_EHV_FIVRA_CPU1")
		)
		(pad "2" smd rect
			(at -0.889 0 270)
			(size 1.016 1.27)
			(layers "B.Cu" "B.Mask" "B.Paste")
			(net "GND")
		)
	)
)
